FILE_TYPE = CONNECTIVITY;
{Allegro Design Entry HDL 17.4-2019 S026 (4007227) 1/17/2022}
"PAGE_NUMBER" = 317;
0"NC";
1"P5E_CPU0_P1_TX_BUF_C_DP<13>";
2"PRSNT_CABLE_SWB_B2_N";
3"NC_J107_A1";
4"P5E_CPU0_P1_TX_BUF_C_DP<9>";
5"P5E_CPU0_P1_TX_BUF_C_DN<9>";
6"GND\g";
7"P5E_CPU0_P0_TX_BUF_C_DP<9>";
8"P5E_CPU0_P1_RX_BUF_DP<9>";
9"P5E_CPU0_P1_RX_BUF_DN<9>";
10"P5E_CPU0_P0_RX_BUF_DP<9>";
11"P5E_CPU0_P0_RX_BUF_DN<9>";
12"P5E_CPU0_P0_RX_BUF_DN<8>";
13"P5E_CPU0_P1_TX_BUF_C_DP<10>";
14"P5E_CPU0_P1_TX_BUF_C_DN<10>";
15"P5E_CPU0_P0_TX_BUF_C_DP<10>";
16"P5E_CPU0_P0_TX_BUF_C_DN<10>";
17"P5E_CPU0_P1_RX_BUF_DP<10>";
18"P5E_CPU0_P1_RX_BUF_DN<10>";
19"P5E_CPU0_P0_RX_BUF_DP<10>";
20"P5E_CPU0_P0_RX_BUF_DN<10>";
21"NC_J107_A3";
22"NC_J107_N4";
23"P5E_CPU0_P0_RX_BUF_DP<14>";
24"P5E_CPU0_P0_RX_BUF_DN<14>";
25"SWB_HSC_PWRGD";
26"GND\g";
27"P5E_CPU0_P1_TX_BUF_C_DP<11>";
28"P5E_CPU0_P1_TX_BUF_C_DN<11>";
29"P5E_CPU0_P0_TX_BUF_C_DP<11>";
30"P5E_CPU0_P1_TX_BUF_C_DP<8>";
31"P5E_CPU0_P0_TX_BUF_C_DP<8>";
32"P5E_CPU0_P1_RX_BUF_DP<8>";
33"P5E_CPU0_P0_TX_BUF_C_DN<11>";
34"P5E_CPU0_P1_RX_BUF_DP<11>";
35"NC_J107_A5";
36"P5E_CPU0_P1_TX_BUF_C_DP<12>";
37"P5E_CPU0_P1_TX_BUF_C_DN<12>";
38"P5E_CPU0_P0_TX_BUF_C_DP<12>";
39"P5E_CPU0_P0_TX_BUF_C_DN<12>";
40"P5E_CPU0_P1_TX_BUF_C_DN<13>";
41"P5E_CPU0_P0_TX_BUF_C_DP<13>";
42"P5E_CPU0_P1_RX_BUF_DP<13>";
43"P5E_CPU0_P1_RX_BUF_DN<13>";
44"P5E_CPU0_P0_RX_BUF_DN<13>";
45"P5E_CPU0_P0_RX_BUF_DP<13>";
46"P5E_CPU0_P1_TX_BUF_C_DP<14>";
47"SWB_HSC_EN_BUF";
48"P5E_CPU0_P1_TX_BUF_C_DP<15>";
49"P5E_CPU0_P1_TX_BUF_C_DN<15>";
50"P5E_CPU0_P1_RX_BUF_DN<14>";
51"P5E_CPU0_P0_TX_BUF_C_DN<14>";
52"P5E_CPU0_P0_TX_BUF_C_DP<14>";
53"P5E_CPU0_P1_RX_BUF_DP<14>";
54"P5E_CPU0_P0_TX_BUF_C_DP<15>";
55"P5E_CPU0_P0_TX_BUF_C_DN<15>";
56"P5E_CPU0_P1_RX_BUF_DP<15>";
57"P5E_CPU0_P1_RX_BUF_DN<15>";
58"P5E_CPU0_P0_RX_BUF_DP<12>";
59"P5E_CPU0_P1_RX_BUF_DN<12>";
60"P5E_CPU0_P1_RX_BUF_DP<12>";
61"NC_J107_N6";
62"P5E_CPU0_P1_TX_BUF_C_DN<14>";
63"P5E_CPU0_P0_TX_BUF_C_DN<13>";
64"P5E_CPU0_P1_TX_BUF_C_DN<8>";
65"P5E_CPU0_P0_TX_BUF_C_DN<8>";
66"P5E_CPU0_P1_RX_BUF_DN<8>";
67"P5E_CPU0_P0_TX_BUF_C_DN<9>";
68"P5E_CPU0_P1_RX_BUF_DN<11>";
69"P5E_CPU0_P0_RX_BUF_DN<12>";
70"P5E_CPU0_P0_RX_BUF_DP<15>";
71"P5E_CPU0_P0_RX_BUF_DN<15>";
72"P5E_CPU0_P0_RX_BUF_DP<8>";
73"P5E_CPU0_P0_RX_BUF_DP<11>";
74"P5E_CPU0_P0_RX_BUF_DN<11>";
%"UNIVERSAL_GND"
"1","(-2100,-1650)","0","pure_quanta_power","I13";
;
CDS_LIB"pure_quanta_power"
HDL_POWER"GND";
"A"26;
%"UNIVERSAL_GND"
"1","(2350,-1700)","0","pure_quanta_power","I48";
;
CDS_LIB"pure_quanta_power"
HDL_POWER"GND";
"A"6;
%"CONN112_10137002101LF"
"2","(3500,250)","0","pure_quanta","I49";
;
LOCATION"J107"
$SEC"2"
CDS_SEC"2"
PART_TYPE"THLF"
MATERIAL"IO"
CDS_LIB"pure_quanta"
CDS_LMAN_SYM_OUTLINE"-775,1650,775,-1650"
VALUE"CONN112_10137002-101LF"
NEEDS_NO_SIZE"TRUE"
PART_NUMBER"DFHSB2FR012";
"N4"
$PN"N4"22;
"M4"
$PN"M4"6;
"N3"
$PN"N3"6;
"M3"
$PN"M3"13;
"N2"
$PN"N2"2;
"M2"
$PN"M2"6;
"N1"
$PN"N1"6;
"M1"
$PN"M1"30;
"L1"
$PN"L1"64;
"L2"
$PN"L2"4;
"L3"
$PN"L3"14;
"L4"
$PN"L4"27;
"K1"
$PN"K1"6;
"K2"
$PN"K2"5;
"K3"
$PN"K3"6;
"K4"
$PN"K4"28;
"J1"
$PN"J1"31;
"J2"
$PN"J2"6;
"J3"
$PN"J3"15;
"J4"
$PN"J4"6;
"I1"
$PN"I1"65;
"I2"
$PN"I2"7;
"I3"
$PN"I3"16;
"I4"
$PN"I4"29;
"H1"
$PN"H1"6;
"H2"
$PN"H2"67;
"H3"
$PN"H3"6;
"H4"
$PN"H4"33;
"G1"
$PN"G1"32;
"G2"
$PN"G2"6;
"G3"
$PN"G3"17;
"G4"
$PN"G4"6;
"F1"
$PN"F1"66;
"F2"
$PN"F2"8;
"F3"
$PN"F3"18;
"F4"
$PN"F4"34;
"E1"
$PN"E1"6;
"E2"
$PN"E2"9;
"E3"
$PN"E3"6;
"E4"
$PN"E4"68;
"D1"
$PN"D1"72;
"D2"
$PN"D2"6;
"D3"
$PN"D3"19;
"D4"
$PN"D4"6;
"C1"
$PN"C1"12;
"C2"
$PN"C2"10;
"C3"
$PN"C3"20;
"C4"
$PN"C4"73;
"B1"
$PN"B1"6;
"B2"
$PN"B2"11;
"B3"
$PN"B3"6;
"B4"
$PN"B4"74;
"A1"
$PN"A1"3;
"A2"
$PN"A2"6;
"A3"
$PN"A3"21;
"A4"
$PN"A4"6;
%"CONN112_10137002101LF"
"1","(-1000,250)","0","pure_quanta","I70";
;
LOCATION"J107"
$SEC"1"
CDS_SEC"1"
MATERIAL"IO"
PART_TYPE"THLF"
CDS_LIB"pure_quanta"
CDS_LMAN_SYM_OUTLINE"-775,1650,775,-1650"
NEEDS_NO_SIZE"TRUE"
VALUE"CONN112_10137002-101LF"
PART_NUMBER"DFHSB2FR012";
"N8"
$PN"N8"47;
"M8"
$PN"M8"26;
"N7"
$PN"N7"26;
"M7"
$PN"M7"46;
"N6"
$PN"N6"61;
"M6"
$PN"M6"26;
"N5"
$PN"N5"26;
"M5"
$PN"M5"36;
"L5"
$PN"L5"37;
"L6"
$PN"L6"1;
"L7"
$PN"L7"62;
"L8"
$PN"L8"48;
"K5"
$PN"K5"26;
"K6"
$PN"K6"40;
"K7"
$PN"K7"26;
"K8"
$PN"K8"49;
"J5"
$PN"J5"38;
"J6"
$PN"J6"26;
"J7"
$PN"J7"52;
"J8"
$PN"J8"26;
"I5"
$PN"I5"39;
"I6"
$PN"I6"41;
"I7"
$PN"I7"51;
"I8"
$PN"I8"54;
"H5"
$PN"H5"26;
"H6"
$PN"H6"63;
"H7"
$PN"H7"26;
"H8"
$PN"H8"55;
"G5"
$PN"G5"60;
"G6"
$PN"G6"26;
"G7"
$PN"G7"53;
"G8"
$PN"G8"26;
"F5"
$PN"F5"59;
"F6"
$PN"F6"42;
"F7"
$PN"F7"50;
"F8"
$PN"F8"56;
"E5"
$PN"E5"26;
"E6"
$PN"E6"43;
"E7"
$PN"E7"26;
"E8"
$PN"E8"57;
"D5"
$PN"D5"58;
"D6"
$PN"D6"26;
"D7"
$PN"D7"23;
"D8"
$PN"D8"26;
"C5"
$PN"C5"69;
"C6"
$PN"C6"45;
"C7"
$PN"C7"24;
"C8"
$PN"C8"70;
"B5"
$PN"B5"26;
"B6"
$PN"B6"44;
"B7"
$PN"B7"26;
"B8"
$PN"B8"71;
"A5"
$PN"A5"35;
"A6"
$PN"A6"26;
"A7"
$PN"A7"25;
"A8"
$PN"A8"26;
END.
